(kicad_pcb
	(version 20260206)
	(generator "pcbnew")
	(generator_version "10.0")
	(general
		(thickness 1.6)
		(legacy_teardrops no)
	)
	(paper "A4")
	(title_block
		(title "04192023_DAF0TMB3IC0_F0TG_MB_C_brd_V02_OCP.brd")
		(comment 1 "Grand Teton / footprints 4466-4472 of 8354")
	)
	(layers
		(0 "F.Cu" signal "TOP")
		(4 "In1.Cu" signal "GND")
		(6 "In2.Cu" signal "IN1")
		(8 "In3.Cu" signal "GND1")
		(10 "In4.Cu" signal "IN2")
		(12 "In5.Cu" signal "GND2")
		(14 "In6.Cu" signal "IN3")
		(16 "In7.Cu" signal "GND3")
		(18 "In8.Cu" signal "VCC")
		(20 "In9.Cu" signal "VCC1")
		(22 "In10.Cu" signal "GND4")
		(24 "In11.Cu" signal "IN4")
		(26 "In12.Cu" signal "GND5")
		(28 "In13.Cu" signal "IN5")
		(30 "In14.Cu" signal "GND6")
		(32 "In15.Cu" signal "IN6")
		(34 "In16.Cu" signal "GND7")
		(2 "B.Cu" signal "BOTTOM")
		(9 "F.Adhes" user "F.Adhesive")
		(11 "B.Adhes" user "B.Adhesive")
		(13 "F.Paste" user "Package Geometry/Pastemask Top")
		(15 "B.Paste" user "Package Geometry/Pastemask Bottom")
		(5 "F.SilkS" user "Ref Des/Silkscreen Top")
		(7 "B.SilkS" user "Ref Des/Silkscreen Bottom")
		(1 "F.Mask" user "Board Geometry/Soldermask Top")
		(3 "B.Mask" user "Board Geometry/Soldermask Bottom")
		(17 "Dwgs.User" user "User.Drawings")
		(19 "Cmts.User" user "User.Comments")
		(21 "Eco1.User" user "User.Eco1")
		(23 "Eco2.User" user "User.Eco2")
		(25 "Edge.Cuts" user "Board Geometry/Outline")
		(27 "Margin" user)
		(31 "F.CrtYd" user "Package Geometry/Place Bound Top")
		(29 "B.CrtYd" user "Package Geometry/Place Bound Bottom")
		(35 "F.Fab" user "Ref Des/Assembly Top")
		(33 "B.Fab" user "Ref Des/Assembly Bottom")
	)
	(footprint ""
		(layer "F.Cu")
		(at 29.214064 -75.234038 -90)
		(property "Reference" "R6181"
			(at 0 0 270)
			(layer "F.SilkS")
			(hide yes)
			(effects
				(font
					(size 1.27 1.27)
				)
			)
		)
		(property "Value" ""
			(at 0 0 270)
			(layer "F.Fab")
			(effects
				(font
					(size 1.27 1.27)
				)
			)
		)
		(duplicate_pad_numbers_are_jumpers no)
		(fp_line
			(start -0.7874 0.4064)
			(end -0.7874 -0.4064)
			(stroke
				(width 0.1524)
				(type default)
			)
			(layer "F.SilkS")
		)
		(fp_line
			(start 0.7874 0.4064)
			(end -0.7874 0.4064)
			(stroke
				(width 0.1524)
				(type default)
			)
			(layer "F.SilkS")
		)
		(fp_line
			(start -0.7874 -0.4064)
			(end 0.7874 -0.4064)
			(stroke
				(width 0.1524)
				(type default)
			)
			(layer "F.SilkS")
		)
		(fp_line
			(start 0.7874 -0.4064)
			(end 0.7874 0.4064)
			(stroke
				(width 0.1524)
				(type default)
			)
			(layer "F.SilkS")
		)
		(fp_line
			(start -0.67945 0.3048)
			(end -0.67945 -0.305054)
			(stroke
				(width 0.1)
				(type default)
			)
			(layer "F.Fab")
		)
		(fp_line
			(start -0.12065 0.3048)
			(end -0.67945 0.3048)
			(stroke
				(width 0.1)
				(type default)
			)
			(layer "F.Fab")
		)
		(fp_line
			(start 0.120396 0.3048)
			(end 0.120396 0.2794)
			(stroke
				(width 0.1)
				(type default)
			)
			(layer "F.Fab")
		)
		(fp_line
			(start 0.67945 0.3048)
			(end 0.120396 0.3048)
			(stroke
				(width 0.1)
				(type default)
			)
			(layer "F.Fab")
		)
		(fp_line
			(start -0.12065 0.2794)
			(end -0.12065 0.3048)
			(stroke
				(width 0.1)
				(type default)
			)
			(layer "F.Fab")
		)
		(fp_line
			(start 0.120396 0.2794)
			(end -0.12065 0.2794)
			(stroke
				(width 0.1)
				(type default)
			)
			(layer "F.Fab")
		)
		(fp_line
			(start -0.12065 -0.2794)
			(end 0.12065 -0.2794)
			(stroke
				(width 0.1)
				(type default)
			)
			(layer "F.Fab")
		)
		(fp_line
			(start 0.12065 -0.2794)
			(end 0.12065 -0.3048)
			(stroke
				(width 0.1)
				(type default)
			)
			(layer "F.Fab")
		)
		(fp_line
			(start 0.12065 -0.3048)
			(end 0.67945 -0.3048)
			(stroke
				(width 0.1)
				(type default)
			)
			(layer "F.Fab")
		)
		(fp_line
			(start 0.67945 -0.3048)
			(end 0.67945 0.3048)
			(stroke
				(width 0.1)
				(type default)
			)
			(layer "F.Fab")
		)
		(fp_line
			(start -0.67945 -0.305054)
			(end -0.12065 -0.305054)
			(stroke
				(width 0.1)
				(type default)
			)
			(layer "F.Fab")
		)
		(fp_line
			(start -0.12065 -0.305054)
			(end -0.12065 -0.2794)
			(stroke
				(width 0.1)
				(type default)
			)
			(layer "F.Fab")
		)
		(pad "1" smd circle
			(at -0.40005 0 270)
			(size 0 0)
			(layers "F.Cu" "F.Mask" "F.Paste")
			(net "P3V3_AUX")
		)
		(pad "2" smd circle
			(at 0.40005 0 270)
			(size 0 0)
			(layers "F.Cu" "F.Mask" "F.Paste")
			(net "PU_U212_EN_N")
		)
	)
	(footprint ""
		(layer "F.Cu")
		(at 414.331912 -363.790992 180)
		(property "Reference" "C197"
			(at 0 0 180)
			(layer "F.SilkS")
			(hide yes)
			(effects
				(font
					(size 1.27 1.27)
				)
			)
		)
		(property "Value" ""
			(at 0 0 180)
			(layer "F.Fab")
			(effects
				(font
					(size 1.27 1.27)
				)
			)
		)
		(duplicate_pad_numbers_are_jumpers no)
		(fp_line
			(start 0.7874 0.4064)
			(end -0.7874 0.4064)
			(stroke
				(width 0.1524)
				(type default)
			)
			(layer "F.SilkS")
		)
		(fp_line
			(start 0.7874 -0.4064)
			(end 0.7874 0.4064)
			(stroke
				(width 0.1524)
				(type default)
			)
			(layer "F.SilkS")
		)
		(fp_line
			(start -0.7874 0.4064)
			(end -0.7874 -0.4064)
			(stroke
				(width 0.1524)
				(type default)
			)
			(layer "F.SilkS")
		)
		(fp_line
			(start -0.7874 -0.4064)
			(end 0.7874 -0.4064)
			(stroke
				(width 0.1524)
				(type default)
			)
			(layer "F.SilkS")
		)
		(fp_line
			(start 0.67945 0.3048)
			(end 0.120396 0.3048)
			(stroke
				(width 0.1)
				(type default)
			)
			(layer "F.Fab")
		)
		(fp_line
			(start 0.67945 -0.3048)
			(end 0.67945 0.3048)
			(stroke
				(width 0.1)
				(type default)
			)
			(layer "F.Fab")
		)
		(fp_line
			(start 0.12065 -0.2794)
			(end 0.12065 -0.3048)
			(stroke
				(width 0.1)
				(type default)
			)
			(layer "F.Fab")
		)
		(fp_line
			(start 0.12065 -0.3048)
			(end 0.67945 -0.3048)
			(stroke
				(width 0.1)
				(type default)
			)
			(layer "F.Fab")
		)
		(fp_line
			(start 0.120396 0.3048)
			(end 0.120396 0.2794)
			(stroke
				(width 0.1)
				(type default)
			)
			(layer "F.Fab")
		)
		(fp_line
			(start 0.120396 0.2794)
			(end -0.12065 0.2794)
			(stroke
				(width 0.1)
				(type default)
			)
			(layer "F.Fab")
		)
		(fp_line
			(start -0.12065 0.3048)
			(end -0.67945 0.3048)
			(stroke
				(width 0.1)
				(type default)
			)
			(layer "F.Fab")
		)
		(fp_line
			(start -0.12065 0.2794)
			(end -0.12065 0.3048)
			(stroke
				(width 0.1)
				(type default)
			)
			(layer "F.Fab")
		)
		(fp_line
			(start -0.12065 -0.2794)
			(end 0.12065 -0.2794)
			(stroke
				(width 0.1)
				(type default)
			)
			(layer "F.Fab")
		)
		(fp_line
			(start -0.12065 -0.305054)
			(end -0.12065 -0.2794)
			(stroke
				(width 0.1)
				(type default)
			)
			(layer "F.Fab")
		)
		(fp_line
			(start -0.67945 0.3048)
			(end -0.67945 -0.305054)
			(stroke
				(width 0.1)
				(type default)
			)
			(layer "F.Fab")
		)
		(fp_line
			(start -0.67945 -0.305054)
			(end -0.12065 -0.305054)
			(stroke
				(width 0.1)
				(type default)
			)
			(layer "F.Fab")
		)
		(pad "1" smd circle
			(at -0.40005 0 180)
			(size 0 0)
			(layers "F.Cu" "F.Mask" "F.Paste")
			(net "PVDD11_S3_P0_EN_R")
		)
		(pad "2" smd circle
			(at 0.40005 0 180)
			(size 0 0)
			(layers "F.Cu" "F.Mask" "F.Paste")
			(net "GND")
		)
	)
	(footprint ""
		(layer "F.Cu")
		(at 217.066114 -126.710694)
		(property "Reference" "R6781"
			(at 0 0 0)
			(layer "F.SilkS")
			(hide yes)
			(effects
				(font
					(size 1.27 1.27)
				)
			)
		)
		(property "Value" ""
			(at 0 0 0)
			(layer "F.Fab")
			(effects
				(font
					(size 1.27 1.27)
				)
			)
		)
		(duplicate_pad_numbers_are_jumpers no)
		(fp_line
			(start -0.7874 -0.4064)
			(end 0.7874 -0.4064)
			(stroke
				(width 0.1524)
				(type default)
			)
			(layer "F.SilkS")
		)
		(fp_line
			(start -0.7874 0.4064)
			(end -0.7874 -0.4064)
			(stroke
				(width 0.1524)
				(type default)
			)
			(layer "F.SilkS")
		)
		(fp_line
			(start 0.7874 -0.4064)
			(end 0.7874 0.4064)
			(stroke
				(width 0.1524)
				(type default)
			)
			(layer "F.SilkS")
		)
		(fp_line
			(start 0.7874 0.4064)
			(end -0.7874 0.4064)
			(stroke
				(width 0.1524)
				(type default)
			)
			(layer "F.SilkS")
		)
		(fp_line
			(start -0.67945 -0.305054)
			(end -0.12065 -0.305054)
			(stroke
				(width 0.1)
				(type default)
			)
			(layer "F.Fab")
		)
		(fp_line
			(start -0.67945 0.3048)
			(end -0.67945 -0.305054)
			(stroke
				(width 0.1)
				(type default)
			)
			(layer "F.Fab")
		)
		(fp_line
			(start -0.12065 -0.305054)
			(end -0.12065 -0.2794)
			(stroke
				(width 0.1)
				(type default)
			)
			(layer "F.Fab")
		)
		(fp_line
			(start -0.12065 -0.2794)
			(end 0.12065 -0.2794)
			(stroke
				(width 0.1)
				(type default)
			)
			(layer "F.Fab")
		)
		(fp_line
			(start -0.12065 0.2794)
			(end -0.12065 0.3048)
			(stroke
				(width 0.1)
				(type default)
			)
			(layer "F.Fab")
		)
		(fp_line
			(start -0.12065 0.3048)
			(end -0.67945 0.3048)
			(stroke
				(width 0.1)
				(type default)
			)
			(layer "F.Fab")
		)
		(fp_line
			(start 0.120396 0.2794)
			(end -0.12065 0.2794)
			(stroke
				(width 0.1)
				(type default)
			)
			(layer "F.Fab")
		)
		(fp_line
			(start 0.120396 0.3048)
			(end 0.120396 0.2794)
			(stroke
				(width 0.1)
				(type default)
			)
			(layer "F.Fab")
		)
		(fp_line
			(start 0.12065 -0.3048)
			(end 0.67945 -0.3048)
			(stroke
				(width 0.1)
				(type default)
			)
			(layer "F.Fab")
		)
		(fp_line
			(start 0.12065 -0.2794)
			(end 0.12065 -0.3048)
			(stroke
				(width 0.1)
				(type default)
			)
			(layer "F.Fab")
		)
		(fp_line
			(start 0.67945 -0.3048)
			(end 0.67945 0.3048)
			(stroke
				(width 0.1)
				(type default)
			)
			(layer "F.Fab")
		)
		(fp_line
			(start 0.67945 0.3048)
			(end 0.120396 0.3048)
			(stroke
				(width 0.1)
				(type default)
			)
			(layer "F.Fab")
		)
		(pad "1" smd circle
			(at -0.40005 0)
			(size 0 0)
			(layers "F.Cu" "F.Mask" "F.Paste")
			(net "RST_SMB_RT_ROM_R2_N")
		)
		(pad "2" smd circle
			(at 0.40005 0)
			(size 0 0)
			(layers "F.Cu" "F.Mask" "F.Paste")
			(net "RST_SMB_RT_ROM_R1_N")
		)
	)
	(footprint ""
		(layer "F.Cu")
		(at 398.893538 -392.1252)
		(property "Reference" "R1078"
			(at 0 0 0)
			(layer "F.SilkS")
			(hide yes)
			(effects
				(font
					(size 1.27 1.27)
				)
			)
		)
		(property "Value" ""
			(at 0 0 0)
			(layer "F.Fab")
			(effects
				(font
					(size 1.27 1.27)
				)
			)
		)
		(duplicate_pad_numbers_are_jumpers no)
		(fp_line
			(start -0.32512 -0.175006)
			(end 0.32512 -0.175006)
			(stroke
				(width 0.1)
				(type default)
			)
			(layer "F.Fab")
		)
		(fp_line
			(start -0.32512 0.175006)
			(end -0.32512 -0.175006)
			(stroke
				(width 0.1)
				(type default)
			)
			(layer "F.Fab")
		)
		(fp_line
			(start 0.32512 -0.175006)
			(end 0.32512 0.175006)
			(stroke
				(width 0.1)
				(type default)
			)
			(layer "F.Fab")
		)
		(fp_line
			(start 0.32512 0.175006)
			(end -0.32512 0.175006)
			(stroke
				(width 0.1)
				(type default)
			)
			(layer "F.Fab")
		)
		(pad "1" smd rect
			(at -0.2667 0)
			(size 0.3048 0.381)
			(layers "F.Cu" "F.Mask" "F.Paste")
			(net "TEST2_RT_CPU0_P2")
		)
		(pad "2" smd rect
			(at 0.2667 0 180)
			(size 0.3048 0.381)
			(layers "F.Cu" "F.Mask" "F.Paste")
			(net "GND")
		)
	)
	(footprint ""
		(layer "F.Cu")
		(at 448.32778 -65.792858 -90)
		(property "Reference" "C1333"
			(at 0 0 270)
			(layer "F.SilkS")
			(hide yes)
			(effects
				(font
					(size 1.27 1.27)
				)
			)
		)
		(property "Value" ""
			(at 0 0 270)
			(layer "F.Fab")
			(effects
				(font
					(size 1.27 1.27)
				)
			)
		)
		(duplicate_pad_numbers_are_jumpers no)
		(fp_line
			(start -1.524 0.762)
			(end -1.524 -0.762)
			(stroke
				(width 0.1524)
				(type default)
			)
			(layer "F.SilkS")
		)
		(fp_line
			(start 1.524 0.762)
			(end -1.524 0.762)
			(stroke
				(width 0.1524)
				(type default)
			)
			(layer "F.SilkS")
		)
		(fp_line
			(start -1.524 -0.762)
			(end 1.524 -0.762)
			(stroke
				(width 0.1524)
				(type default)
			)
			(layer "F.SilkS")
		)
		(fp_line
			(start 1.524 -0.762)
			(end 1.524 0.762)
			(stroke
				(width 0.1524)
				(type default)
			)
			(layer "F.SilkS")
		)
		(fp_line
			(start -1.1049 0.724916)
			(end 1.1049 0.724916)
			(stroke
				(width 0.1)
				(type default)
			)
			(layer "F.Fab")
		)
		(fp_line
			(start 1.1049 0.724916)
			(end 1.1049 -0.724916)
			(stroke
				(width 0.1)
				(type default)
			)
			(layer "F.Fab")
		)
		(fp_line
			(start -1.1049 -0.724916)
			(end -1.1049 0.724916)
			(stroke
				(width 0.1)
				(type default)
			)
			(layer "F.Fab")
		)
		(fp_line
			(start 1.1049 -0.724916)
			(end -1.1049 -0.724916)
			(stroke
				(width 0.1)
				(type default)
			)
			(layer "F.Fab")
		)
		(pad "1" smd rect
			(at -0.889 0 90)
			(size 1.016 1.27)
			(layers "F.Cu" "F.Mask" "F.Paste")
			(net "P3V3_AUX")
		)
		(pad "2" smd rect
			(at 0.889 0 90)
			(size 1.016 1.27)
			(layers "F.Cu" "F.Mask" "F.Paste")
			(net "GND")
		)
	)
	(footprint ""
		(layer "F.Cu")
		(at 322.837048 -46.986698 180)
		(property "Reference" "R3680"
			(at 0 0 180)
			(layer "F.SilkS")
			(hide yes)
			(effects
				(font
					(size 1.27 1.27)
				)
			)
		)
		(property "Value" ""
			(at 0 0 180)
			(layer "F.Fab")
			(effects
				(font
					(size 1.27 1.27)
				)
			)
		)
		(duplicate_pad_numbers_are_jumpers no)
		(fp_line
			(start 0.7874 0.4064)
			(end -0.7874 0.4064)
			(stroke
				(width 0.1524)
				(type default)
			)
			(layer "F.SilkS")
		)
		(fp_line
			(start 0.7874 -0.4064)
			(end 0.7874 0.4064)
			(stroke
				(width 0.1524)
				(type default)
			)
			(layer "F.SilkS")
		)
		(fp_line
			(start -0.7874 0.4064)
			(end -0.7874 -0.4064)
			(stroke
				(width 0.1524)
				(type default)
			)
			(layer "F.SilkS")
		)
		(fp_line
			(start -0.7874 -0.4064)
			(end 0.7874 -0.4064)
			(stroke
				(width 0.1524)
				(type default)
			)
			(layer "F.SilkS")
		)
		(fp_line
			(start 0.67945 0.3048)
			(end 0.120396 0.3048)
			(stroke
				(width 0.1)
				(type default)
			)
			(layer "F.Fab")
		)
		(fp_line
			(start 0.67945 -0.3048)
			(end 0.67945 0.3048)
			(stroke
				(width 0.1)
				(type default)
			)
			(layer "F.Fab")
		)
		(fp_line
			(start 0.12065 -0.2794)
			(end 0.12065 -0.3048)
			(stroke
				(width 0.1)
				(type default)
			)
			(layer "F.Fab")
		)
		(fp_line
			(start 0.12065 -0.3048)
			(end 0.67945 -0.3048)
			(stroke
				(width 0.1)
				(type default)
			)
			(layer "F.Fab")
		)
		(fp_line
			(start 0.120396 0.3048)
			(end 0.120396 0.2794)
			(stroke
				(width 0.1)
				(type default)
			)
			(layer "F.Fab")
		)
		(fp_line
			(start 0.120396 0.2794)
			(end -0.12065 0.2794)
			(stroke
				(width 0.1)
				(type default)
			)
			(layer "F.Fab")
		)
		(fp_line
			(start -0.12065 0.3048)
			(end -0.67945 0.3048)
			(stroke
				(width 0.1)
				(type default)
			)
			(layer "F.Fab")
		)
		(fp_line
			(start -0.12065 0.2794)
			(end -0.12065 0.3048)
			(stroke
				(width 0.1)
				(type default)
			)
			(layer "F.Fab")
		)
		(fp_line
			(start -0.12065 -0.2794)
			(end 0.12065 -0.2794)
			(stroke
				(width 0.1)
				(type default)
			)
			(layer "F.Fab")
		)
		(fp_line
			(start -0.12065 -0.305054)
			(end -0.12065 -0.2794)
			(stroke
				(width 0.1)
				(type default)
			)
			(layer "F.Fab")
		)
		(fp_line
			(start -0.67945 0.3048)
			(end -0.67945 -0.305054)
			(stroke
				(width 0.1)
				(type default)
			)
			(layer "F.Fab")
		)
		(fp_line
			(start -0.67945 -0.305054)
			(end -0.12065 -0.305054)
			(stroke
				(width 0.1)
				(type default)
			)
			(layer "F.Fab")
		)
		(pad "1" smd rect
			(at -0.40005 0)
			(size 0.4572 0.508)
			(layers "F.Cu" "F.Mask" "F.Paste")
			(net "P12V_AUX_ADC")
		)
		(pad "2" smd rect
			(at 0.40005 0)
			(size 0.4572 0.508)
			(layers "F.Cu" "F.Mask" "F.Paste")
			(net "P12V_AUX_ADC_TIC")
		)
	)
	(footprint ""
		(layer "F.Cu")
		(at 443.308486 -21.676106 180)
		(property "Reference" "R1284"
			(at 0 0 180)
			(layer "F.SilkS")
			(hide yes)
			(effects
				(font
					(size 1.27 1.27)
				)
			)
		)
		(property "Value" ""
			(at 0 0 180)
			(layer "F.Fab")
			(effects
				(font
					(size 1.27 1.27)
				)
			)
		)
		(duplicate_pad_numbers_are_jumpers no)
		(fp_line
			(start 0.7874 0.4064)
			(end -0.7874 0.4064)
			(stroke
				(width 0.1524)
				(type default)
			)
			(layer "F.SilkS")
		)
		(fp_line
			(start 0.7874 -0.4064)
			(end 0.7874 0.4064)
			(stroke
				(width 0.1524)
				(type default)
			)
			(layer "F.SilkS")
		)
		(fp_line
			(start -0.7874 0.4064)
			(end -0.7874 -0.4064)
			(stroke
				(width 0.1524)
				(type default)
			)
			(layer "F.SilkS")
		)
		(fp_line
			(start -0.7874 -0.4064)
			(end 0.7874 -0.4064)
			(stroke
				(width 0.1524)
				(type default)
			)
			(layer "F.SilkS")
		)
		(fp_line
			(start 0.67945 0.3048)
			(end 0.120396 0.3048)
			(stroke
				(width 0.1)
				(type default)
			)
			(layer "F.Fab")
		)
		(fp_line
			(start 0.67945 -0.3048)
			(end 0.67945 0.3048)
			(stroke
				(width 0.1)
				(type default)
			)
			(layer "F.Fab")
		)
		(fp_line
			(start 0.12065 -0.2794)
			(end 0.12065 -0.3048)
			(stroke
				(width 0.1)
				(type default)
			)
			(layer "F.Fab")
		)
		(fp_line
			(start 0.12065 -0.3048)
			(end 0.67945 -0.3048)
			(stroke
				(width 0.1)
				(type default)
			)
			(layer "F.Fab")
		)
		(fp_line
			(start 0.120396 0.3048)
			(end 0.120396 0.2794)
			(stroke
				(width 0.1)
				(type default)
			)
			(layer "F.Fab")
		)
		(fp_line
			(start 0.120396 0.2794)
			(end -0.12065 0.2794)
			(stroke
				(width 0.1)
				(type default)
			)
			(layer "F.Fab")
		)
		(fp_line
			(start -0.12065 0.3048)
			(end -0.67945 0.3048)
			(stroke
				(width 0.1)
				(type default)
			)
			(layer "F.Fab")
		)
		(fp_line
			(start -0.12065 0.2794)
			(end -0.12065 0.3048)
			(stroke
				(width 0.1)
				(type default)
			)
			(layer "F.Fab")
		)
		(fp_line
			(start -0.12065 -0.2794)
			(end 0.12065 -0.2794)
			(stroke
				(width 0.1)
				(type default)
			)
			(layer "F.Fab")
		)
		(fp_line
			(start -0.12065 -0.305054)
			(end -0.12065 -0.2794)
			(stroke
				(width 0.1)
				(type default)
			)
			(layer "F.Fab")
		)
		(fp_line
			(start -0.67945 0.3048)
			(end -0.67945 -0.305054)
			(stroke
				(width 0.1)
				(type default)
			)
			(layer "F.Fab")
		)
		(fp_line
			(start -0.67945 -0.305054)
			(end -0.12065 -0.305054)
			(stroke
				(width 0.1)
				(type default)
			)
			(layer "F.Fab")
		)
		(pad "1" smd circle
			(at -0.40005 0 180)
			(size 0 0)
			(layers "F.Cu" "F.Mask" "F.Paste")
			(net "P12V_OCP_SFF")
		)
		(pad "2" smd circle
			(at 0.40005 0 180)
			(size 0 0)
			(layers "F.Cu" "F.Mask" "F.Paste")
			(net "VSENSE_P12V_INA230_6_INP")
		)
	)
)
